(kicad_pcb
	(version 20241229)
	(generator "pcbnew")
	(generator_version "9.0")
	(general
		(thickness 1.61)
		(legacy_teardrops no)
	)
	(paper "A3")
	(title_block
		(title "SO-DIMM DDR5 Tester")
		(date "2025-11-26")
		(rev "1.3.0")
		(comment 9 "footprints 303-309 of 627")
	)
	(layers
		(0 "F.Cu" signal)
		(4 "In1.Cu" power)
		(6 "In2.Cu" mixed)
		(8 "In3.Cu" power)
		(10 "In4.Cu" mixed)
		(12 "In5.Cu" power)
		(14 "In6.Cu" mixed)
		(16 "In7.Cu" power)
		(18 "In8.Cu" power)
		(20 "In9.Cu" mixed)
		(22 "In10.Cu" power)
		(2 "B.Cu" signal)
		(9 "F.Adhes" user "F.Adhesive")
		(11 "B.Adhes" user "B.Adhesive")
		(13 "F.Paste" user)
		(15 "B.Paste" user)
		(5 "F.SilkS" user "F.Silkscreen")
		(7 "B.SilkS" user "B.Silkscreen")
		(1 "F.Mask" user)
		(3 "B.Mask" user)
		(17 "Dwgs.User" user "User.Drawings")
		(19 "Cmts.User" user "User.Comments")
		(21 "Eco1.User" user "User.Eco1")
		(23 "Eco2.User" user "User.Eco2")
		(25 "Edge.Cuts" user)
		(27 "Margin" user)
		(31 "F.CrtYd" user "F.Courtyard")
		(29 "B.CrtYd" user "B.Courtyard")
		(35 "F.Fab" user)
		(33 "B.Fab" user)
	)
	(footprint "antmicro-footprints:R_0402_1005Metric"
		(layer "F.Cu")
		(at 99.8 136.07 -90)
		(descr "Resistor SMD 0402")
		(tags "resistor SMD 0402")
		(property "Reference" "R125"
			(at -1.122484 -0.772697 270)
			(layer "F.SilkS")
			(hide yes)
			(effects
				(font
					(size 0.7 0.7)
					(thickness 0.15)
				)
				(justify left bottom)
			)
		)
		(property "Value" "R_4k7_0402"
			(at -1.011843 1.772047 270)
			(layer "F.Fab")
			(effects
				(font
					(size 0.7 0.7)
					(thickness 0.15)
				)
				(justify left bottom)
			)
		)
		(property "Datasheet" "https://www.bourns.com/docs/product-datasheets/cr.pdf"
			(at 0 0 270)
			(layer "F.Fab")
			(hide yes)
			(effects
				(font
					(size 1.27 1.27)
					(thickness 0.15)
				)
			)
		)
		(property "Author" "Antmicro"
			(at -36.27 235.87 0)
			(layer "F.Fab")
			(hide yes)
			(effects
				(font
					(size 1 1)
					(thickness 0.15)
				)
			)
		)
		(property "License" "Apache-2.0"
			(at -36.27 235.87 0)
			(layer "F.Fab")
			(hide yes)
			(effects
				(font
					(size 1 1)
					(thickness 0.15)
				)
			)
		)
		(property "MPN" "CR0402-FX-4701GLF"
			(at -36.27 235.87 0)
			(layer "F.Fab")
			(hide yes)
			(effects
				(font
					(size 1 1)
					(thickness 0.15)
				)
			)
		)
		(property "Manufacturer" "Bourns"
			(at -36.27 235.87 0)
			(layer "F.Fab")
			(hide yes)
			(effects
				(font
					(size 1 1)
					(thickness 0.15)
				)
			)
		)
		(property "Tolerance" "1%"
			(at -36.27 235.87 0)
			(layer "F.Fab")
			(hide yes)
			(effects
				(font
					(size 1 1)
					(thickness 0.15)
				)
			)
		)
		(property "Val" "4k7"
			(at -36.27 235.87 0)
			(layer "F.Fab")
			(hide yes)
			(effects
				(font
					(size 1 1)
					(thickness 0.15)
				)
			)
		)
		(sheetname "/I^{2}C/")
		(sheetfile "i2c.kicad_sch")
		(attr smd)
		(fp_rect
			(start -0.93 -0.47)
			(end 0.93 0.47)
			(stroke
				(width 0.05)
				(type solid)
			)
			(fill no)
			(layer "F.CrtYd")
		)
		(fp_rect
			(start -0.5 -0.25)
			(end 0.5 0.25)
			(stroke
				(width 0.15)
				(type solid)
			)
			(fill no)
			(layer "F.Fab")
		)
		(pad "1" smd roundrect
			(at -0.485 0 270)
			(size 0.59 0.64)
			(layers "F.Cu" "F.Mask" "F.Paste")
			(roundrect_rratio 0.25)
			(net 267 "VDDSPD")
			(pintype "passive")
		)
		(pad "2" smd roundrect
			(at 0.485 0 270)
			(size 0.59 0.64)
			(layers "F.Cu" "F.Mask" "F.Paste")
			(roundrect_rratio 0.25)
			(net 50 "/DDR5 SODIMM/DDR.SCL")
			(pintype "passive")
		)
	)
	(footprint "antmicro-footprints:R_0402_1005Metric"
		(layer "F.Cu")
		(at 177.100501 197.776 90)
		(descr "Resistor SMD 0402")
		(tags "resistor SMD 0402")
		(property "Reference" "R186"
			(at -3.624 0.299499 90)
			(layer "F.SilkS")
			(effects
				(font
					(size 0.7 0.7)
					(thickness 0.15)
				)
				(justify left bottom)
			)
		)
		(property "Value" "R_205k_0402"
			(at -1.011843 1.772047 90)
			(layer "F.Fab")
			(effects
				(font
					(size 0.7 0.7)
					(thickness 0.15)
				)
				(justify left bottom)
			)
		)
		(property "Datasheet" "https://www.bourns.com/docs/product-datasheets/cr.pdf"
			(at 0 0 90)
			(layer "F.Fab")
			(hide yes)
			(effects
				(font
					(size 1.27 1.27)
					(thickness 0.15)
				)
			)
		)
		(property "Author" "Antmicro"
			(at 374.876501 20.675499 0)
			(layer "F.Fab")
			(hide yes)
			(effects
				(font
					(size 1 1)
					(thickness 0.15)
				)
			)
		)
		(property "License" "Apache-2.0"
			(at 374.876501 20.675499 0)
			(layer "F.Fab")
			(hide yes)
			(effects
				(font
					(size 1 1)
					(thickness 0.15)
				)
			)
		)
		(property "MPN" "CR0402-FX-2053GLF"
			(at 374.876501 20.675499 0)
			(layer "F.Fab")
			(hide yes)
			(effects
				(font
					(size 1 1)
					(thickness 0.15)
				)
			)
		)
		(property "Manufacturer" "Bourns"
			(at 374.876501 20.675499 0)
			(layer "F.Fab")
			(hide yes)
			(effects
				(font
					(size 1 1)
					(thickness 0.15)
				)
			)
		)
		(property "Tolerance" "1%"
			(at 374.876501 20.675499 0)
			(layer "F.Fab")
			(hide yes)
			(effects
				(font
					(size 1 1)
					(thickness 0.15)
				)
			)
		)
		(property "Val" "205k"
			(at 374.876501 20.675499 0)
			(layer "F.Fab")
			(hide yes)
			(effects
				(font
					(size 1 1)
					(thickness 0.15)
				)
			)
		)
		(sheetname "/Supply/")
		(sheetfile "supply.kicad_sch")
		(attr smd)
		(fp_rect
			(start -0.93 -0.47)
			(end 0.93 0.47)
			(stroke
				(width 0.05)
				(type solid)
			)
			(fill no)
			(layer "F.CrtYd")
		)
		(fp_rect
			(start -0.5 -0.25)
			(end 0.5 0.25)
			(stroke
				(width 0.15)
				(type solid)
			)
			(fill no)
			(layer "F.Fab")
		)
		(pad "1" smd roundrect
			(at -0.485 0 90)
			(size 0.59 0.64)
			(layers "F.Cu" "F.Mask" "F.Paste")
			(roundrect_rratio 0.25)
			(net 1 "GND")
			(pintype "passive")
		)
		(pad "2" smd roundrect
			(at 0.485 0 90)
			(size 0.59 0.64)
			(layers "F.Cu" "F.Mask" "F.Paste")
			(roundrect_rratio 0.25)
			(net 303 "Net-(C221-Pad1)")
			(pintype "passive")
		)
	)
	(footprint "antmicro-footprints:C_0603_1608Metric"
		(layer "F.Cu")
		(at 191.245501 185.523 -90)
		(descr "Capacitor SMD 0603")
		(tags "capacitor 0603")
		(property "Reference" "C186"
			(at -1.42757 -1.000252 270)
			(layer "F.SilkS")
			(hide yes)
			(effects
				(font
					(size 0.7 0.7)
					(thickness 0.15)
				)
				(justify left bottom)
			)
		)
		(property "Value" "C_22u_0603"
			(at -1.42757 1.770288 270)
			(layer "F.Fab")
			(effects
				(font
					(size 0.7 0.7)
					(thickness 0.15)
				)
				(justify left bottom)
			)
		)
		(property "Datasheet" "https://www.murata.com/products/productdetail?partno=GRM188R60J226MEA0%23"
			(at 0 0 270)
			(layer "F.Fab")
			(hide yes)
			(effects
				(font
					(size 1.27 1.27)
					(thickness 0.15)
				)
			)
		)
		(property "Author" "Antmicro"
			(at 5.722501 376.768501 0)
			(layer "F.Fab")
			(hide yes)
			(effects
				(font
					(size 1 1)
					(thickness 0.15)
				)
			)
		)
		(property "Dielectric" ""
			(at 5.722501 376.768501 0)
			(layer "F.Fab")
			(hide yes)
			(effects
				(font
					(size 1 1)
					(thickness 0.15)
				)
			)
		)
		(property "License" "Apache-2.0"
			(at 5.722501 376.768501 0)
			(layer "F.Fab")
			(hide yes)
			(effects
				(font
					(size 1 1)
					(thickness 0.15)
				)
			)
		)
		(property "MPN" "GRM188R60J226MEA0D"
			(at 5.722501 376.768501 0)
			(layer "F.Fab")
			(hide yes)
			(effects
				(font
					(size 1 1)
					(thickness 0.15)
				)
			)
		)
		(property "Manufacturer" "Murata"
			(at 5.722501 376.768501 0)
			(layer "F.Fab")
			(hide yes)
			(effects
				(font
					(size 1 1)
					(thickness 0.15)
				)
			)
		)
		(property "Val" "22u"
			(at 5.722501 376.768501 0)
			(layer "F.Fab")
			(hide yes)
			(effects
				(font
					(size 1 1)
					(thickness 0.15)
				)
			)
		)
		(property "Voltage" ""
			(at 5.722501 376.768501 0)
			(layer "F.Fab")
			(hide yes)
			(effects
				(font
					(size 1 1)
					(thickness 0.15)
				)
			)
		)
		(sheetname "/Supply/")
		(sheetfile "supply.kicad_sch")
		(attr smd)
		(fp_line
			(start -0.3 0.3)
			(end 0.3 0.3)
			(stroke
				(width 0.15)
				(type solid)
			)
			(layer "F.SilkS")
		)
		(fp_line
			(start -0.3 -0.3)
			(end 0.3 -0.3)
			(stroke
				(width 0.15)
				(type solid)
			)
			(layer "F.SilkS")
		)
		(fp_rect
			(start -1.24 -0.7)
			(end 1.24 0.7)
			(stroke
				(width 0.05)
				(type solid)
			)
			(fill no)
			(layer "F.CrtYd")
		)
		(fp_rect
			(start -0.8 -0.4)
			(end 0.8 0.4)
			(stroke
				(width 0.15)
				(type solid)
			)
			(fill no)
			(layer "F.Fab")
		)
		(pad "1" smd roundrect
			(at -0.7 0 270)
			(size 0.6 0.8)
			(layers "F.Cu" "F.Mask" "F.Paste")
			(roundrect_rratio 0.2)
			(net 1 "GND")
			(pintype "passive")
		)
		(pad "2" smd roundrect
			(at 0.7 0 270)
			(size 0.6 0.8)
			(layers "F.Cu" "F.Mask" "F.Paste")
			(roundrect_rratio 0.2)
			(net 42 "/Supply/MGTAVCC_local")
			(pintype "passive")
		)
	)
	(footprint "antmicro-footprints:C_0603_1608Metric"
		(layer "F.Cu")
		(at 192.668501 168.072 -90)
		(descr "Capacitor SMD 0603")
		(tags "capacitor 0603")
		(property "Reference" "C190"
			(at -1.42757 -1.000252 270)
			(layer "F.SilkS")
			(hide yes)
			(effects
				(font
					(size 0.7 0.7)
					(thickness 0.15)
				)
				(justify left bottom)
			)
		)
		(property "Value" "C_22u_0603"
			(at -1.42757 1.770288 270)
			(layer "F.Fab")
			(effects
				(font
					(size 0.7 0.7)
					(thickness 0.15)
				)
				(justify left bottom)
			)
		)
		(property "Datasheet" "https://www.murata.com/products/productdetail?partno=GRM188R60J226MEA0%23"
			(at 0 0 270)
			(layer "F.Fab")
			(hide yes)
			(effects
				(font
					(size 1.27 1.27)
					(thickness 0.15)
				)
			)
		)
		(property "Author" "Antmicro"
			(at 24.596501 360.740501 0)
			(layer "F.Fab")
			(hide yes)
			(effects
				(font
					(size 1 1)
					(thickness 0.15)
				)
			)
		)
		(property "Dielectric" ""
			(at 24.596501 360.740501 0)
			(layer "F.Fab")
			(hide yes)
			(effects
				(font
					(size 1 1)
					(thickness 0.15)
				)
			)
		)
		(property "License" "Apache-2.0"
			(at 24.596501 360.740501 0)
			(layer "F.Fab")
			(hide yes)
			(effects
				(font
					(size 1 1)
					(thickness 0.15)
				)
			)
		)
		(property "MPN" "GRM188R60J226MEA0D"
			(at 24.596501 360.740501 0)
			(layer "F.Fab")
			(hide yes)
			(effects
				(font
					(size 1 1)
					(thickness 0.15)
				)
			)
		)
		(property "Manufacturer" "Murata"
			(at 24.596501 360.740501 0)
			(layer "F.Fab")
			(hide yes)
			(effects
				(font
					(size 1 1)
					(thickness 0.15)
				)
			)
		)
		(property "Val" "22u"
			(at 24.596501 360.740501 0)
			(layer "F.Fab")
			(hide yes)
			(effects
				(font
					(size 1 1)
					(thickness 0.15)
				)
			)
		)
		(property "Voltage" ""
			(at 24.596501 360.740501 0)
			(layer "F.Fab")
			(hide yes)
			(effects
				(font
					(size 1 1)
					(thickness 0.15)
				)
			)
		)
		(sheetname "/Supply/")
		(sheetfile "supply.kicad_sch")
		(attr smd)
		(fp_line
			(start -0.3 0.3)
			(end 0.3 0.3)
			(stroke
				(width 0.15)
				(type solid)
			)
			(layer "F.SilkS")
		)
		(fp_line
			(start -0.3 -0.3)
			(end 0.3 -0.3)
			(stroke
				(width 0.15)
				(type solid)
			)
			(layer "F.SilkS")
		)
		(fp_rect
			(start -1.24 -0.7)
			(end 1.24 0.7)
			(stroke
				(width 0.05)
				(type solid)
			)
			(fill no)
			(layer "F.CrtYd")
		)
		(fp_rect
			(start -0.8 -0.4)
			(end 0.8 0.4)
			(stroke
				(width 0.15)
				(type solid)
			)
			(fill no)
			(layer "F.Fab")
		)
		(pad "1" smd roundrect
			(at -0.7 0 270)
			(size 0.6 0.8)
			(layers "F.Cu" "F.Mask" "F.Paste")
			(roundrect_rratio 0.2)
			(net 1 "GND")
			(pintype "passive")
		)
		(pad "2" smd roundrect
			(at 0.7 0 270)
			(size 0.6 0.8)
			(layers "F.Cu" "F.Mask" "F.Paste")
			(roundrect_rratio 0.2)
			(net 52 "/Supply/3V3_local")
			(pintype "passive")
		)
	)
	(footprint "antmicro-footprints:R_0402_1005Metric"
		(layer "F.Cu")
		(at 177.9 180.215)
		(descr "Resistor SMD 0402")
		(tags "resistor SMD 0402")
		(property "Reference" "R138"
			(at -1.122484 -0.772697 0)
			(layer "F.SilkS")
			(hide yes)
			(effects
				(font
					(size 0.7 0.7)
					(thickness 0.15)
				)
				(justify left bottom)
			)
		)
		(property "Value" "R_0R_0402"
			(at -1.011843 1.772047 0)
			(layer "F.Fab")
			(effects
				(font
					(size 0.7 0.7)
					(thickness 0.15)
				)
				(justify left bottom)
			)
		)
		(property "Datasheet" "https://industrial.panasonic.com/cdbs/www-data/pdf/RDA0000/AOA0000C301.pdf"
			(at 0 0 0)
			(layer "F.Fab")
			(hide yes)
			(effects
				(font
					(size 1.27 1.27)
					(thickness 0.15)
				)
			)
		)
		(property "Author" "Antmicro"
			(at 0 0 0)
			(layer "F.Fab")
			(hide yes)
			(effects
				(font
					(size 1 1)
					(thickness 0.15)
				)
			)
		)
		(property "Current" "1A"
			(at 0 0 0)
			(layer "F.Fab")
			(hide yes)
			(effects
				(font
					(size 1 1)
					(thickness 0.15)
				)
			)
		)
		(property "License" "Apache-2.0"
			(at 0 0 0)
			(layer "F.Fab")
			(hide yes)
			(effects
				(font
					(size 1 1)
					(thickness 0.15)
				)
			)
		)
		(property "MPN" "ERJ2GE0R00X"
			(at 0 0 0)
			(layer "F.Fab")
			(hide yes)
			(effects
				(font
					(size 1 1)
					(thickness 0.15)
				)
			)
		)
		(property "Manufacturer" "Panasonic"
			(at 0 0 0)
			(layer "F.Fab")
			(hide yes)
			(effects
				(font
					(size 1 1)
					(thickness 0.15)
				)
			)
		)
		(property "Tolerance" ""
			(at 0 0 0)
			(layer "F.Fab")
			(hide yes)
			(effects
				(font
					(size 1 1)
					(thickness 0.15)
				)
			)
		)
		(property "Val" "0R"
			(at 0 0 0)
			(layer "F.Fab")
			(hide yes)
			(effects
				(font
					(size 1 1)
					(thickness 0.15)
				)
			)
		)
		(sheetname "/Supply/")
		(sheetfile "supply.kicad_sch")
		(attr smd)
		(fp_rect
			(start -0.93 -0.47)
			(end 0.93 0.47)
			(stroke
				(width 0.05)
				(type solid)
			)
			(fill no)
			(layer "F.CrtYd")
		)
		(fp_rect
			(start -0.5 -0.25)
			(end 0.5 0.25)
			(stroke
				(width 0.15)
				(type solid)
			)
			(fill no)
			(layer "F.Fab")
		)
		(pad "1" smd roundrect
			(at -0.485 0)
			(size 0.59 0.64)
			(layers "F.Cu" "F.Mask" "F.Paste")
			(roundrect_rratio 0.25)
			(net 240 "POWER")
			(pintype "passive")
		)
		(pad "2" smd roundrect
			(at 0.485 0)
			(size 0.59 0.64)
			(layers "F.Cu" "F.Mask" "F.Paste")
			(roundrect_rratio 0.25)
			(net 282 "/Supply/PG3")
			(pintype "passive")
		)
	)
	(footprint "antmicro-footprints:R_0402_1005Metric"
		(layer "F.Cu")
		(at 176.619501 194.214502)
		(descr "Resistor SMD 0402")
		(tags "resistor SMD 0402")
		(property "Reference" "R181"
			(at -1.069501 1.385498 0)
			(layer "F.SilkS")
			(effects
				(font
					(size 0.7 0.7)
					(thickness 0.15)
				)
				(justify left bottom)
			)
		)
		(property "Value" "R_10k_0402"
			(at -1.011843 1.772047 0)
			(layer "F.Fab")
			(effects
				(font
					(size 0.7 0.7)
					(thickness 0.15)
				)
				(justify left bottom)
			)
		)
		(property "Datasheet" "https://www.bourns.com/docs/product-datasheets/cr.pdf"
			(at 0 0 0)
			(layer "F.Fab")
			(hide yes)
			(effects
				(font
					(size 1.27 1.27)
					(thickness 0.15)
				)
			)
		)
		(property "Author" "Antmicro"
			(at 0 0 0)
			(layer "F.Fab")
			(hide yes)
			(effects
				(font
					(size 1 1)
					(thickness 0.15)
				)
			)
		)
		(property "License" "Apache-2.0"
			(at 0 0 0)
			(layer "F.Fab")
			(hide yes)
			(effects
				(font
					(size 1 1)
					(thickness 0.15)
				)
			)
		)
		(property "MPN" "CR0402-FX-1002GLF"
			(at 0 0 0)
			(layer "F.Fab")
			(hide yes)
			(effects
				(font
					(size 1 1)
					(thickness 0.15)
				)
			)
		)
		(property "Manufacturer" "Bourns"
			(at 0 0 0)
			(layer "F.Fab")
			(hide yes)
			(effects
				(font
					(size 1 1)
					(thickness 0.15)
				)
			)
		)
		(property "Tolerance" "1%"
			(at 0 0 0)
			(layer "F.Fab")
			(hide yes)
			(effects
				(font
					(size 1 1)
					(thickness 0.15)
				)
			)
		)
		(property "Val" "10k"
			(at 0 0 0)
			(layer "F.Fab")
			(hide yes)
			(effects
				(font
					(size 1 1)
					(thickness 0.15)
				)
			)
		)
		(sheetname "/Supply/")
		(sheetfile "supply.kicad_sch")
		(attr smd)
		(fp_rect
			(start -0.93 -0.47)
			(end 0.93 0.47)
			(stroke
				(width 0.05)
				(type solid)
			)
			(fill no)
			(layer "F.CrtYd")
		)
		(fp_rect
			(start -0.5 -0.25)
			(end 0.5 0.25)
			(stroke
				(width 0.15)
				(type solid)
			)
			(fill no)
			(layer "F.Fab")
		)
		(pad "1" smd roundrect
			(at -0.485 0)
			(size 0.59 0.64)
			(layers "F.Cu" "F.Mask" "F.Paste")
			(roundrect_rratio 0.25)
			(net 225 "/Supply/1V0_FB")
			(pintype "passive")
		)
		(pad "2" smd roundrect
			(at 0.485 0)
			(size 0.59 0.64)
			(layers "F.Cu" "F.Mask" "F.Paste")
			(roundrect_rratio 0.25)
			(net 303 "Net-(C221-Pad1)")
			(pintype "passive")
		)
	)
	(footprint "antmicro-footprints:NetTie-2_SMD_Pad0.127mm"
		(layer "F.Cu")
		(at 198.675 177.174 180)
		(descr "Net tie, 2 pin, 0.127mm  SMD pads")
		(tags "net tie")
		(property "Reference" "NT11"
			(at -0.128 -1.345 180)
			(layer "F.SilkS")
			(hide yes)
			(effects
				(font
					(size 0.7 0.7)
					(thickness 0.15)
				)
				(justify left bottom)
			)
		)
		(property "Value" "Net-Tie_P0.127mm"
			(at 0 1.199 180)
			(layer "F.Fab")
			(effects
				(font
					(size 0.7 0.7)
					(thickness 0.15)
				)
				(justify left bottom)
			)
		)
		(property "Author" "Antmicro"
			(at 397.35 354.348 0)
			(layer "F.Fab")
			(hide yes)
			(effects
				(font
					(size 1 1)
					(thickness 0.15)
				)
			)
		)
		(property "License" "Apache-2.0"
			(at 397.35 354.348 0)
			(layer "F.Fab")
			(hide yes)
			(effects
				(font
					(size 1 1)
					(thickness 0.15)
				)
			)
		)
		(property "MPN" ""
			(at 397.35 354.348 0)
			(layer "F.Fab")
			(hide yes)
			(effects
				(font
					(size 1 1)
					(thickness 0.15)
				)
			)
		)
		(property "Manufacturer" ""
			(at 397.35 354.348 0)
			(layer "F.Fab")
			(hide yes)
			(effects
				(font
					(size 1 1)
					(thickness 0.15)
				)
			)
		)
		(property ki_fp_filters "Net*Tie*")
		(sheetname "/Supply/")
		(sheetfile "supply.kicad_sch")
		(attr smd exclude_from_pos_files exclude_from_bom)
		(net_tie_pad_groups "1, 2")
		(fp_poly
			(pts
				(xy -0.0635 -0.0635) (xy 0.0625 -0.0635) (xy 0.0625 0.0635) (xy -0.0635 0.0635)
			)
			(stroke
				(width 0)
				(type solid)
			)
			(fill yes)
			(layer "F.Cu")
		)
		(pad "1" smd roundrect
			(at -0.127 0)
			(size 0.127 0.127)
			(layers "F.Cu")
			(roundrect_rratio 0.5)
			(chamfer_ratio 0)
			(chamfer top_left bottom_left)
			(net 237 "/Supply/sp_SEN_-")
			(pinfunction "1")
			(pintype "passive")
		)
		(pad "2" smd roundrect
			(at 0.126 0 180)
			(size 0.127 0.127)
			(layers "F.Cu")
			(roundrect_rratio 0.5)
			(chamfer_ratio 0)
			(chamfer top_left bottom_left)
			(net 239 "/Supply/spare")
			(pinfunction "2")
			(pintype "passive")
		)
	)
)
